# T6G (Grand Teton) — schematic netlist excerpt (pin names and nets, part order shuffled) for the footprints in the layout excerpt that follows; sources: Cadence DE-HDL packaged netlist, KiCad conversion of 04192023_DAF0TMB3IC0_F0TG_MB_C_brd_V02_OCP.brd

C819  Q_CAP_DIFFBUS  DIFF BUS_0.22UF 6.3V 20% X6S  pkg C0201  page 65 : \1\ = P5E_CPU1_P0_TX_C_DP<9> ; \2\ = P5E_CPU1_P0_TX_DP<9>
C2071  Q_CAP  0.1UF 25V 10% X7R  pkg 0402  page 236 : A = VSENSE_P3V3_INA230_2_INP ; B = VSENSE_P3V3_INA230_2_INN
R3660  Q_RES  10K 1% CHIP  pkg 0402LF  page 234 : A = P3V3_AUX ; B = RST_USB_HUB_R_N

(kicad_pcb
	(version 20260206)
	(generator "pcbnew")
	(generator_version "10.0")
	(general
		(thickness 1.6)
		(legacy_teardrops no)
	)
	(paper "A4")
	(title_block
		(title "04192023_DAF0TMB3IC0_F0TG_MB_C_brd_V02_OCP.brd")
		(comment 1 "Grand Teton / footprints 728-730 of 8354")
	)
	(layers
		(0 "F.Cu" signal "TOP")
		(4 "In1.Cu" signal "GND")
		(6 "In2.Cu" signal "IN1")
		(8 "In3.Cu" signal "GND1")
		(10 "In4.Cu" signal "IN2")
		(12 "In5.Cu" signal "GND2")
		(14 "In6.Cu" signal "IN3")
		(16 "In7.Cu" signal "GND3")
		(18 "In8.Cu" signal "VCC")
		(20 "In9.Cu" signal "VCC1")
		(22 "In10.Cu" signal "GND4")
		(24 "In11.Cu" signal "IN4")
		(26 "In12.Cu" signal "GND5")
		(28 "In13.Cu" signal "IN5")
		(30 "In14.Cu" signal "GND6")
		(32 "In15.Cu" signal "IN6")
		(34 "In16.Cu" signal "GND7")
		(2 "B.Cu" signal "BOTTOM")
		(9 "F.Adhes" user "F.Adhesive")
		(11 "B.Adhes" user "B.Adhesive")
		(13 "F.Paste" user "Package Geometry/Pastemask Top")
		(15 "B.Paste" user "Package Geometry/Pastemask Bottom")
		(5 "F.SilkS" user "Ref Des/Silkscreen Top")
		(7 "B.SilkS" user "Ref Des/Silkscreen Bottom")
		(1 "F.Mask" user "Board Geometry/Soldermask Top")
		(3 "B.Mask" user "Board Geometry/Soldermask Bottom")
		(17 "Dwgs.User" user "User.Drawings")
		(19 "Cmts.User" user "User.Comments")
		(21 "Eco1.User" user "User.Eco1")
		(23 "Eco2.User" user "User.Eco2")
		(25 "Edge.Cuts" user "Board Geometry/Outline")
		(27 "Margin" user)
		(31 "F.CrtYd" user "Package Geometry/Place Bound Top")
		(29 "B.CrtYd" user "Package Geometry/Place Bound Bottom")
		(35 "F.Fab" user "Ref Des/Assembly Top")
		(33 "B.Fab" user "Ref Des/Assembly Bottom")
	)
	(footprint ""
		(layer "F.Cu")
		(at 58.305954 -370.57203 -90)
		(property "Reference" "C819"
			(at 0 0 270)
			(layer "F.SilkS")
			(hide yes)
			(effects
				(font
					(size 1.27 1.27)
				)
			)
		)
		(property "Value" ""
			(at 0 0 270)
			(layer "F.Fab")
			(effects
				(font
					(size 1.27 1.27)
				)
			)
		)
		(duplicate_pad_numbers_are_jumpers no)
		(fp_line
			(start -0.299974 0.150114)
			(end -0.299974 -0.150114)
			(stroke
				(width 0.1)
				(type default)
			)
			(layer "F.Fab")
		)
		(fp_line
			(start 0.299974 0.150114)
			(end -0.299974 0.150114)
			(stroke
				(width 0.1)
				(type default)
			)
			(layer "F.Fab")
		)
		(fp_line
			(start -0.299974 -0.150114)
			(end 0.299974 -0.150114)
			(stroke
				(width 0.1)
				(type default)
			)
			(layer "F.Fab")
		)
		(fp_line
			(start 0.299974 -0.150114)
			(end 0.299974 0.150114)
			(stroke
				(width 0.1)
				(type default)
			)
			(layer "F.Fab")
		)
		(pad "1" smd rect
			(at -0.2667 0 270)
			(size 0.3048 0.381)
			(layers "F.Cu" "F.Mask" "F.Paste")
			(net "P5E_CPU1_P0_TX_C_DP<9>")
		)
		(pad "2" smd rect
			(at 0.2667 0 270)
			(size 0.3048 0.381)
			(layers "F.Cu" "F.Mask" "F.Paste")
			(net "P5E_CPU1_P0_TX_DP<9>")
		)
	)
	(footprint ""
		(layer "F.Cu")
		(at 218.130882 -57.399682 -90)
		(property "Reference" "C2071"
			(at 0 0 270)
			(layer "F.SilkS")
			(hide yes)
			(effects
				(font
					(size 1.27 1.27)
				)
			)
		)
		(property "Value" ""
			(at 0 0 270)
			(layer "F.Fab")
			(effects
				(font
					(size 1.27 1.27)
				)
			)
		)
		(duplicate_pad_numbers_are_jumpers no)
		(fp_line
			(start -0.7874 0.4064)
			(end -0.7874 -0.4064)
			(stroke
				(width 0.1524)
				(type default)
			)
			(layer "F.SilkS")
		)
		(fp_line
			(start 0.7874 0.4064)
			(end -0.7874 0.4064)
			(stroke
				(width 0.1524)
				(type default)
			)
			(layer "F.SilkS")
		)
		(fp_line
			(start -0.7874 -0.4064)
			(end 0.7874 -0.4064)
			(stroke
				(width 0.1524)
				(type default)
			)
			(layer "F.SilkS")
		)
		(fp_line
			(start 0.7874 -0.4064)
			(end 0.7874 0.4064)
			(stroke
				(width 0.1524)
				(type default)
			)
			(layer "F.SilkS")
		)
		(fp_line
			(start -0.67945 0.3048)
			(end -0.67945 -0.305054)
			(stroke
				(width 0.1)
				(type default)
			)
			(layer "F.Fab")
		)
		(fp_line
			(start -0.12065 0.3048)
			(end -0.67945 0.3048)
			(stroke
				(width 0.1)
				(type default)
			)
			(layer "F.Fab")
		)
		(fp_line
			(start 0.120396 0.3048)
			(end 0.120396 0.2794)
			(stroke
				(width 0.1)
				(type default)
			)
			(layer "F.Fab")
		)
		(fp_line
			(start 0.67945 0.3048)
			(end 0.120396 0.3048)
			(stroke
				(width 0.1)
				(type default)
			)
			(layer "F.Fab")
		)
		(fp_line
			(start -0.12065 0.2794)
			(end -0.12065 0.3048)
			(stroke
				(width 0.1)
				(type default)
			)
			(layer "F.Fab")
		)
		(fp_line
			(start 0.120396 0.2794)
			(end -0.12065 0.2794)
			(stroke
				(width 0.1)
				(type default)
			)
			(layer "F.Fab")
		)
		(fp_line
			(start -0.12065 -0.2794)
			(end 0.12065 -0.2794)
			(stroke
				(width 0.1)
				(type default)
			)
			(layer "F.Fab")
		)
		(fp_line
			(start 0.12065 -0.2794)
			(end 0.12065 -0.3048)
			(stroke
				(width 0.1)
				(type default)
			)
			(layer "F.Fab")
		)
		(fp_line
			(start 0.12065 -0.3048)
			(end 0.67945 -0.3048)
			(stroke
				(width 0.1)
				(type default)
			)
			(layer "F.Fab")
		)
		(fp_line
			(start 0.67945 -0.3048)
			(end 0.67945 0.3048)
			(stroke
				(width 0.1)
				(type default)
			)
			(layer "F.Fab")
		)
		(fp_line
			(start -0.67945 -0.305054)
			(end -0.12065 -0.305054)
			(stroke
				(width 0.1)
				(type default)
			)
			(layer "F.Fab")
		)
		(fp_line
			(start -0.12065 -0.305054)
			(end -0.12065 -0.2794)
			(stroke
				(width 0.1)
				(type default)
			)
			(layer "F.Fab")
		)
		(pad "1" smd circle
			(at -0.40005 0 270)
			(size 0 0)
			(layers "F.Cu" "F.Mask" "F.Paste")
			(net "VSENSE_P3V3_INA230_2_INP")
		)
		(pad "2" smd circle
			(at 0.40005 0 270)
			(size 0 0)
			(layers "F.Cu" "F.Mask" "F.Paste")
			(net "VSENSE_P3V3_INA230_2_INN")
		)
	)
	(footprint ""
		(layer "F.Cu")
		(at 12.982956 -92.687648 90)
		(property "Reference" "R3660"
			(at 0 0 90)
			(layer "F.SilkS")
			(hide yes)
			(effects
				(font
					(size 1.27 1.27)
				)
			)
		)
		(property "Value" ""
			(at 0 0 90)
			(layer "F.Fab")
			(effects
				(font
					(size 1.27 1.27)
				)
			)
		)
		(duplicate_pad_numbers_are_jumpers no)
		(fp_line
			(start 0.7874 -0.4064)
			(end 0.7874 0.4064)
			(stroke
				(width 0.1524)
				(type default)
			)
			(layer "F.SilkS")
		)
		(fp_line
			(start -0.7874 -0.4064)
			(end 0.7874 -0.4064)
			(stroke
				(width 0.1524)
				(type default)
			)
			(layer "F.SilkS")
		)
		(fp_line
			(start 0.7874 0.4064)
			(end -0.7874 0.4064)
			(stroke
				(width 0.1524)
				(type default)
			)
			(layer "F.SilkS")
		)
		(fp_line
			(start -0.7874 0.4064)
			(end -0.7874 -0.4064)
			(stroke
				(width 0.1524)
				(type default)
			)
			(layer "F.SilkS")
		)
		(fp_line
			(start -0.12065 -0.305054)
			(end -0.12065 -0.2794)
			(stroke
				(width 0.1)
				(type default)
			)
			(layer "F.Fab")
		)
		(fp_line
			(start -0.67945 -0.305054)
			(end -0.12065 -0.305054)
			(stroke
				(width 0.1)
				(type default)
			)
			(layer "F.Fab")
		)
		(fp_line
			(start 0.67945 -0.3048)
			(end 0.67945 0.3048)
			(stroke
				(width 0.1)
				(type default)
			)
			(layer "F.Fab")
		)
		(fp_line
			(start 0.12065 -0.3048)
			(end 0.67945 -0.3048)
			(stroke
				(width 0.1)
				(type default)
			)
			(layer "F.Fab")
		)
		(fp_line
			(start 0.12065 -0.2794)
			(end 0.12065 -0.3048)
			(stroke
				(width 0.1)
				(type default)
			)
			(layer "F.Fab")
		)
		(fp_line
			(start -0.12065 -0.2794)
			(end 0.12065 -0.2794)
			(stroke
				(width 0.1)
				(type default)
			)
			(layer "F.Fab")
		)
		(fp_line
			(start 0.120396 0.2794)
			(end -0.12065 0.2794)
			(stroke
				(width 0.1)
				(type default)
			)
			(layer "F.Fab")
		)
		(fp_line
			(start -0.12065 0.2794)
			(end -0.12065 0.3048)
			(stroke
				(width 0.1)
				(type default)
			)
			(layer "F.Fab")
		)
		(fp_line
			(start 0.67945 0.3048)
			(end 0.120396 0.3048)
			(stroke
				(width 0.1)
				(type default)
			)
			(layer "F.Fab")
		)
		(fp_line
			(start 0.120396 0.3048)
			(end 0.120396 0.2794)
			(stroke
				(width 0.1)
				(type default)
			)
			(layer "F.Fab")
		)
		(fp_line
			(start -0.12065 0.3048)
			(end -0.67945 0.3048)
			(stroke
				(width 0.1)
				(type default)
			)
			(layer "F.Fab")
		)
		(fp_line
			(start -0.67945 0.3048)
			(end -0.67945 -0.305054)
			(stroke
				(width 0.1)
				(type default)
			)
			(layer "F.Fab")
		)
		(pad "1" smd circle
			(at -0.40005 0 90)
			(size 0 0)
			(layers "F.Cu" "F.Mask" "F.Paste")
			(net "P3V3_AUX")
		)
		(pad "2" smd circle
			(at 0.40005 0 90)
			(size 0 0)
			(layers "F.Cu" "F.Mask" "F.Paste")
			(net "RST_USB_HUB_R_N")
		)
	)
)
